(kicad_pcb
	(version 20241229)
	(generator "pcbnew")
	(generator_version "9.0")
	(general
		(thickness 1.711)
		(legacy_teardrops no)
	)
	(paper "A4")
	(title_block
		(title "Antmicro Baseboard for Jetson AGX Thor")
		(date "2026-02-18")
		(rev "1.1.0")
		(company "Antmicro Ltd")
		(comment 1 "www.antmicro.com")
		(comment 9 "footprints 906-909 of 1170")
	)
	(layers
		(0 "F.Cu" signal)
		(4 "In1.Cu" signal)
		(6 "In2.Cu" signal)
		(8 "In3.Cu" signal)
		(10 "In4.Cu" jumper)
		(12 "In5.Cu" signal)
		(14 "In6.Cu" signal)
		(16 "In7.Cu" signal)
		(18 "In8.Cu" signal)
		(2 "B.Cu" signal)
		(9 "F.Adhes" user "F.Adhesive")
		(11 "B.Adhes" user "B.Adhesive")
		(13 "F.Paste" user)
		(15 "B.Paste" user)
		(5 "F.SilkS" user "F.Silkscreen")
		(7 "B.SilkS" user "B.Silkscreen")
		(1 "F.Mask" user)
		(3 "B.Mask" user)
		(17 "Dwgs.User" user "User.Drawings")
		(19 "Cmts.User" user "User.Comments")
		(21 "Eco1.User" user "User.Eco1")
		(23 "Eco2.User" user "User.Eco2")
		(25 "Edge.Cuts" user)
		(27 "Margin" user)
		(31 "F.CrtYd" user "F.Courtyard")
		(29 "B.CrtYd" user "B.Courtyard")
		(35 "F.Fab" user)
		(33 "B.Fab" user)
	)
	(footprint "antmicro-footprints:C_0402_1005Metric"
		(layer "B.Cu")
		(at 225.426 137.86)
		(descr "Capacitor SMD 0402")
		(tags "capacitor SMD 0402")
		(property "Reference" "C178"
			(at -1.8 0.74 0)
			(layer "B.SilkS")
			(effects
				(font
					(size 0.7 0.7)
					(thickness 0.15)
				)
				(justify right top mirror)
			)
		)
		(property "Value" "C_100n_0402"
			(at -1.022927 -2.155213 0)
			(layer "B.Fab")
			(effects
				(font
					(size 0.7 0.7)
					(thickness 0.15)
				)
				(justify right top mirror)
			)
		)
		(property "Datasheet" "https://www.murata.com/products/productdetail?partno=GRM155R61H104KE14%23"
			(at 0 0 0)
			(layer "B.Fab")
			(hide yes)
			(effects
				(font
					(size 1.27 1.27)
					(thickness 0.15)
				)
				(justify mirror)
			)
		)
		(property "Description" "SMD Multilayer Ceramic Capacitor, 0.1 µF, 50 V, 0402 [1005 Metric], ± 10%, X5R, GRM Series"
			(at 0 0 0)
			(layer "B.Fab")
			(hide yes)
			(effects
				(font
					(size 1.27 1.27)
					(thickness 0.15)
				)
				(justify mirror)
			)
		)
		(property "MPN" "GRM155R61H104KE14D"
			(at 0 0 180)
			(unlocked yes)
			(layer "B.Fab")
			(hide yes)
			(effects
				(font
					(size 1 1)
					(thickness 0.15)
				)
				(justify mirror)
			)
		)
		(property "Manufacturer" "Murata"
			(at 0 0 180)
			(unlocked yes)
			(layer "B.Fab")
			(hide yes)
			(effects
				(font
					(size 1 1)
					(thickness 0.15)
				)
				(justify mirror)
			)
		)
		(property "License" "Apache-2.0"
			(at 0 0 180)
			(unlocked yes)
			(layer "B.Fab")
			(hide yes)
			(effects
				(font
					(size 1 1)
					(thickness 0.15)
				)
				(justify mirror)
			)
		)
		(property "Author" "Antmicro"
			(at 0 0 180)
			(unlocked yes)
			(layer "B.Fab")
			(hide yes)
			(effects
				(font
					(size 1 1)
					(thickness 0.15)
				)
				(justify mirror)
			)
		)
		(property "Val" "100n"
			(at 0 0 180)
			(unlocked yes)
			(layer "B.Fab")
			(hide yes)
			(effects
				(font
					(size 1 1)
					(thickness 0.15)
				)
				(justify mirror)
			)
		)
		(property "Voltage" "50V"
			(at 0 0 180)
			(unlocked yes)
			(layer "B.Fab")
			(hide yes)
			(effects
				(font
					(size 1 1)
					(thickness 0.15)
				)
				(justify mirror)
			)
		)
		(property "Dielectric" "X5R"
			(at 0 0 180)
			(unlocked yes)
			(layer "B.Fab")
			(hide yes)
			(effects
				(font
					(size 1 1)
					(thickness 0.15)
				)
				(justify mirror)
			)
		)
		(sheetname "/SFP/")
		(sheetfile "sfp.kicad_sch")
		(attr smd)
		(fp_rect
			(start -0.925 0.47)
			(end 0.925 -0.47)
			(stroke
				(width 0.05)
				(type default)
			)
			(fill no)
			(layer "B.CrtYd")
		)
		(fp_line
			(start -0.494 -0.248)
			(end -0.494 0.25)
			(stroke
				(width 0.15)
				(type solid)
			)
			(layer "B.Fab")
		)
		(fp_line
			(start -0.494 0.25)
			(end 0.504 0.25)
			(stroke
				(width 0.15)
				(type solid)
			)
			(layer "B.Fab")
		)
		(fp_line
			(start 0.504 -0.248)
			(end -0.494 -0.248)
			(stroke
				(width 0.15)
				(type solid)
			)
			(layer "B.Fab")
		)
		(fp_line
			(start 0.504 0.25)
			(end 0.504 -0.248)
			(stroke
				(width 0.15)
				(type solid)
			)
			(layer "B.Fab")
		)
		(fp_text user "${REFERENCE}"
			(at -0.939 -4.599 0)
			(layer "B.Fab")
			(effects
				(font
					(size 0.7 0.7)
					(thickness 0.15)
				)
				(justify right top mirror)
			)
		)
		(fp_text user "License: Apache-2.0"
			(at -0.939 -5.799 0)
			(layer "B.Fab")
			(effects
				(font
					(size 0.7 0.7)
					(thickness 0.15)
				)
				(justify right top mirror)
			)
		)
		(fp_text user "Author: Antmicro"
			(at -0.939 -3.399 0)
			(layer "B.Fab")
			(effects
				(font
					(size 0.7 0.7)
					(thickness 0.15)
				)
				(justify right top mirror)
			)
		)
		(pad "1" smd roundrect
			(at -0.48 0)
			(size 0.59 0.64)
			(layers "B.Cu" "B.Mask" "B.Paste")
			(roundrect_rratio 0.25)
			(net 1 "GND")
			(pintype "passive")
		)
		(pad "2" smd roundrect
			(at 0.48 0)
			(size 0.59 0.64)
			(layers "B.Cu" "B.Mask" "B.Paste")
			(roundrect_rratio 0.25)
			(net 379 "/SFP/SH")
			(pintype "passive")
		)
	)
	(footprint "antmicro-footprints:R_0402_1005Metric"
		(layer "B.Cu")
		(at 223.06 119.9)
		(descr "Resistor SMD 0402")
		(tags "resistor SMD 0402")
		(property "Reference" "R332"
			(at -1.66 -1.5 0)
			(layer "B.SilkS")
			(effects
				(font
					(size 0.7 0.7)
					(thickness 0.15)
				)
				(justify right top mirror)
			)
		)
		(property "Value" "R_10k_0402"
			(at -1.011843 -1.772047 0)
			(layer "B.Fab")
			(effects
				(font
					(size 0.7 0.7)
					(thickness 0.15)
				)
				(justify right top mirror)
			)
		)
		(property "Datasheet" "https://www.bourns.com/docs/product-datasheets/cr.pdf"
			(at 0 0 0)
			(layer "B.Fab")
			(hide yes)
			(effects
				(font
					(size 1.27 1.27)
					(thickness 0.15)
				)
				(justify mirror)
			)
		)
		(property "Description" "SMD Chip Resistor, 10 kohm, ± 1%, 62.5 mW, 0402 [1005 Metric], Thick Film, General Purpose"
			(at 0 0 0)
			(layer "B.Fab")
			(hide yes)
			(effects
				(font
					(size 1.27 1.27)
					(thickness 0.15)
				)
				(justify mirror)
			)
		)
		(property "MPN" "CR0402-FX-1002GLF"
			(at 0 0 180)
			(unlocked yes)
			(layer "B.Fab")
			(hide yes)
			(effects
				(font
					(size 1 1)
					(thickness 0.15)
				)
				(justify mirror)
			)
		)
		(property "Manufacturer" "Bourns"
			(at 0 0 180)
			(unlocked yes)
			(layer "B.Fab")
			(hide yes)
			(effects
				(font
					(size 1 1)
					(thickness 0.15)
				)
				(justify mirror)
			)
		)
		(property "License" "Apache-2.0"
			(at 0 0 180)
			(unlocked yes)
			(layer "B.Fab")
			(hide yes)
			(effects
				(font
					(size 1 1)
					(thickness 0.15)
				)
				(justify mirror)
			)
		)
		(property "Author" "Antmicro"
			(at 0 0 180)
			(unlocked yes)
			(layer "B.Fab")
			(hide yes)
			(effects
				(font
					(size 1 1)
					(thickness 0.15)
				)
				(justify mirror)
			)
		)
		(property "Val" "10k"
			(at 0 0 180)
			(unlocked yes)
			(layer "B.Fab")
			(hide yes)
			(effects
				(font
					(size 1 1)
					(thickness 0.15)
				)
				(justify mirror)
			)
		)
		(property "Tolerance" "1%"
			(at 0 0 180)
			(unlocked yes)
			(layer "B.Fab")
			(hide yes)
			(effects
				(font
					(size 1 1)
					(thickness 0.15)
				)
				(justify mirror)
			)
		)
		(sheetname "/USB Hub/")
		(sheetfile "usb_hub.kicad_sch")
		(attr smd)
		(fp_rect
			(start -0.925 0.47)
			(end 0.925 -0.47)
			(stroke
				(width 0.05)
				(type default)
			)
			(fill no)
			(layer "B.CrtYd")
		)
		(fp_rect
			(start -0.5 0.25)
			(end 0.5 -0.25)
			(stroke
				(width 0.15)
				(type solid)
			)
			(fill no)
			(layer "B.Fab")
		)
		(fp_text user "Author: Antmicro"
			(at -0.95 -4.169 0)
			(layer "B.Fab")
			(effects
				(font
					(size 0.7 0.7)
					(thickness 0.15)
				)
				(justify right top mirror)
			)
		)
		(fp_text user "${REFERENCE}"
			(at -0.95 -3.168 0)
			(layer "B.Fab")
			(effects
				(font
					(size 0.7 0.7)
					(thickness 0.15)
				)
				(justify right top mirror)
			)
		)
		(fp_text user "License: Apache-2.0"
			(at -0.95 -5.169 0)
			(layer "B.Fab")
			(effects
				(font
					(size 0.7 0.7)
					(thickness 0.15)
				)
				(justify right top mirror)
			)
		)
		(pad "1" smd roundrect
			(at -0.48 0)
			(size 0.59 0.64)
			(layers "B.Cu" "B.Mask" "B.Paste")
			(roundrect_rratio 0.25)
			(net 5 "+5V")
			(pintype "passive")
		)
		(pad "2" smd roundrect
			(at 0.48 0)
			(size 0.59 0.64)
			(layers "B.Cu" "B.Mask" "B.Paste")
			(roundrect_rratio 0.25)
			(net 1332 "Net-(Q27-D1)")
			(pintype "passive")
		)
	)
	(footprint "antmicro-footprints:R_0402_1005Metric"
		(layer "B.Cu")
		(at 203.4 102.8)
		(descr "Resistor SMD 0402")
		(tags "resistor SMD 0402")
		(property "Reference" "R254"
			(at 1 -0.4 0)
			(layer "B.SilkS")
			(effects
				(font
					(size 0.7 0.7)
					(thickness 0.15)
				)
				(justify right top mirror)
			)
		)
		(property "Value" "R_10k_0402"
			(at -1.011843 -1.772046 0)
			(layer "B.Fab")
			(effects
				(font
					(size 0.7 0.7)
					(thickness 0.15)
				)
				(justify right top mirror)
			)
		)
		(property "Datasheet" "https://www.bourns.com/docs/product-datasheets/cr.pdf"
			(at 0 0 0)
			(layer "B.Fab")
			(hide yes)
			(effects
				(font
					(size 1.27 1.27)
					(thickness 0.15)
				)
				(justify mirror)
			)
		)
		(property "Description" "SMD Chip Resistor, 10 kohm, ± 1%, 62.5 mW, 0402 [1005 Metric], Thick Film, General Purpose"
			(at 0 0 0)
			(layer "B.Fab")
			(hide yes)
			(effects
				(font
					(size 1.27 1.27)
					(thickness 0.15)
				)
				(justify mirror)
			)
		)
		(property "Manufacturer" "Bourns"
			(at 0 0 180)
			(unlocked yes)
			(layer "B.Fab")
			(hide yes)
			(effects
				(font
					(size 1 1)
					(thickness 0.15)
				)
				(justify mirror)
			)
		)
		(property "MPN" "CR0402-FX-1002GLF"
			(at 0 0 180)
			(unlocked yes)
			(layer "B.Fab")
			(hide yes)
			(effects
				(font
					(size 1 1)
					(thickness 0.15)
				)
				(justify mirror)
			)
		)
		(property "Val" "10k"
			(at 0 0 180)
			(unlocked yes)
			(layer "B.Fab")
			(hide yes)
			(effects
				(font
					(size 1 1)
					(thickness 0.15)
				)
				(justify mirror)
			)
		)
		(property "License" "Apache-2.0"
			(at 0 0 180)
			(unlocked yes)
			(layer "B.Fab")
			(hide yes)
			(effects
				(font
					(size 1 1)
					(thickness 0.15)
				)
				(justify mirror)
			)
		)
		(property "Author" "Antmicro"
			(at 0 0 180)
			(unlocked yes)
			(layer "B.Fab")
			(hide yes)
			(effects
				(font
					(size 1 1)
					(thickness 0.15)
				)
				(justify mirror)
			)
		)
		(property "Tolerance" "1%"
			(at 0 0 180)
			(unlocked yes)
			(layer "B.Fab")
			(hide yes)
			(effects
				(font
					(size 1 1)
					(thickness 0.15)
				)
				(justify mirror)
			)
		)
		(sheetname "/Recovery USB/")
		(sheetfile "recovery_usb.kicad_sch")
		(attr smd exclude_from_pos_files exclude_from_bom dnp)
		(fp_poly
			(pts
				(xy -0.925 0.47) (xy 0.925 0.47) (xy 0.925 -0.47) (xy -0.925 -0.47)
			)
			(stroke
				(width 0.05)
				(type default)
			)
			(fill no)
			(layer "B.CrtYd")
		)
		(fp_poly
			(pts
				(xy -0.5 0.25) (xy 0.5 0.25) (xy 0.5 -0.25) (xy -0.5 -0.25)
			)
			(stroke
				(width 0.15)
				(type solid)
			)
			(fill no)
			(layer "B.Fab")
		)
		(fp_text user "Author: Antmicro"
			(at -0.95 -4.169 0)
			(layer "B.Fab")
			(effects
				(font
					(size 0.7 0.7)
					(thickness 0.15)
				)
				(justify right top mirror)
			)
		)
		(fp_text user "License: Apache-2.0"
			(at -0.949999 -5.169 0)
			(layer "B.Fab")
			(effects
				(font
					(size 0.7 0.7)
					(thickness 0.15)
				)
				(justify right top mirror)
			)
		)
		(fp_text user "${REFERENCE}"
			(at -0.95 -3.168 0)
			(layer "B.Fab")
			(effects
				(font
					(size 0.7 0.7)
					(thickness 0.15)
				)
				(justify right top mirror)
			)
		)
		(pad "1" smd roundrect
			(at -0.48 0)
			(size 0.59 0.64)
			(layers "B.Cu" "B.Mask" "B.Paste")
			(roundrect_rratio 0.25)
			(net 5 "+5V")
			(pintype "passive")
		)
		(pad "2" smd roundrect
			(at 0.48 0)
			(size 0.59 0.64)
			(layers "B.Cu" "B.Mask" "B.Paste")
			(roundrect_rratio 0.25)
			(net 1012 "/Recovery USB/USBC2_PORT")
			(pintype "passive")
		)
	)
	(footprint "antmicro-footprints:LED_0603_1608Metric_G"
		(layer "B.Cu")
		(at 61.5 82.51)
		(descr "LED SMD 0603 Green")
		(tags "LED SMD 0603 Green")
		(property "Reference" "D29"
			(at -1.02 -2.6 0)
			(layer "B.SilkS")
			(effects
				(font
					(size 0.7 0.7)
					(thickness 0.15)
				)
				(justify right top mirror)
			)
		)
		(property "Value" "LED_G_0603_LTST-C190GKT"
			(at -0.001 -1.599 0)
			(layer "B.Fab")
			(effects
				(font
					(size 0.7 0.7)
					(thickness 0.15)
				)
				(justify right top mirror)
			)
		)
		(property "Datasheet" "https://media.digikey.com/pdf/Data%20Sheets/Lite-On%20PDFs/LTST-C190GKT.pdf"
			(at 0 0 0)
			(layer "B.Fab")
			(hide yes)
			(effects
				(font
					(size 1.27 1.27)
					(thickness 0.15)
				)
				(justify mirror)
			)
		)
		(property "Description" "LED, Green, SMD, 0603, 20 mA, 2.1 V, 569 nm"
			(at 0 0 0)
			(layer "B.Fab")
			(hide yes)
			(effects
				(font
					(size 1.27 1.27)
					(thickness 0.15)
				)
				(justify mirror)
			)
		)
		(property "MPN" "LTST-C190GKT"
			(at 0 0 180)
			(unlocked yes)
			(layer "B.Fab")
			(hide yes)
			(effects
				(font
					(size 1 1)
					(thickness 0.15)
				)
				(justify mirror)
			)
		)
		(property "Manufacturer" "Lite-On"
			(at 0 0 180)
			(unlocked yes)
			(layer "B.Fab")
			(hide yes)
			(effects
				(font
					(size 1 1)
					(thickness 0.15)
				)
				(justify mirror)
			)
		)
		(property "Author" "Antmicro"
			(at 0 0 180)
			(unlocked yes)
			(layer "B.Fab")
			(hide yes)
			(effects
				(font
					(size 1 1)
					(thickness 0.15)
				)
				(justify mirror)
			)
		)
		(property "License" "Apache-2.0"
			(at 0 0 180)
			(unlocked yes)
			(layer "B.Fab")
			(hide yes)
			(effects
				(font
					(size 1 1)
					(thickness 0.15)
				)
				(justify mirror)
			)
		)
		(property "Color" "Green"
			(at 0 0 180)
			(unlocked yes)
			(layer "B.Fab")
			(hide yes)
			(effects
				(font
					(size 1 1)
					(thickness 0.15)
				)
				(justify mirror)
			)
		)
		(sheetname "/CSI/")
		(sheetfile "csi.kicad_sch")
		(attr smd)
		(fp_line
			(start -1.18 0.319)
			(end -1.18 -0.321)
			(stroke
				(width 0.15)
				(type solid)
			)
			(layer "B.SilkS")
		)
		(fp_line
			(start -0.094672 -0.201008)
			(end -0.094672 0.198992)
			(stroke
				(width 0.1)
				(type solid)
			)
			(layer "B.SilkS")
		)
		(fp_line
			(start -0.094672 -0.001008)
			(end -0.24 -0.001008)
			(stroke
				(width 0.1)
				(type solid)
			)
			(layer "B.SilkS")
		)
		(fp_line
			(start -0.094672 -0.001008)
			(end 0.105328 0.198992)
			(stroke
				(width 0.1)
				(type solid)
			)
			(layer "B.SilkS")
		)
		(fp_line
			(start 0.105328 -0.201008)
			(end -0.094672 -0.001008)
			(stroke
				(width 0.1)
				(type solid)
			)
			(layer "B.SilkS")
		)
		(fp_line
			(start 0.105328 -0.201008)
			(end 0.105328 0.198992)
			(stroke
				(width 0.1)
				(type solid)
			)
			(layer "B.SilkS")
		)
		(fp_line
			(start 0.105328 -0.001008)
			(end 0.24 -0.001)
			(stroke
				(width 0.1)
				(type solid)
			)
			(layer "B.SilkS")
		)
		(fp_line
			(start 0.22 -0.35)
			(end -0.22 -0.35)
			(stroke
				(width 0.15)
				(type solid)
			)
			(layer "B.SilkS")
		)
		(fp_line
			(start 0.22 0.35)
			(end -0.22 0.35)
			(stroke
				(width 0.15)
				(type solid)
			)
			(layer "B.SilkS")
		)
		(fp_rect
			(start 1.25 -0.65)
			(end -1.25 0.65)
			(stroke
				(width 0.05)
				(type solid)
			)
			(fill no)
			(layer "B.CrtYd")
		)
		(fp_line
			(start -0.199 -0.2)
			(end -0.199 -0.1)
			(stroke
				(width 0.15)
				(type solid)
			)
			(layer "B.Fab")
		)
		(fp_line
			(start -0.199 0)
			(end -0.597 0)
			(stroke
				(width 0.15)
				(type solid)
			)
			(layer "B.Fab")
		)
		(fp_line
			(start -0.199 0.202)
			(end -0.199 -0.1)
			(stroke
				(width 0.15)
				(type solid)
			)
			(layer "B.Fab")
		)
		(fp_line
			(start -0.101 0)
			(end 0.201 -0.2)
			(stroke
				(width 0.15)
				(type solid)
			)
			(layer "B.Fab")
		)
		(fp_line
			(start 0.201 -0.2)
			(end 0.201 0)
			(stroke
				(width 0.15)
				(type solid)
			)
			(layer "B.Fab")
		)
		(fp_line
			(start 0.201 0)
			(end 0.201 0.202)
			(stroke
				(width 0.15)
				(type solid)
			)
			(layer "B.Fab")
		)
		(fp_line
			(start 0.201 0.202)
			(end -0.101 0)
			(stroke
				(width 0.15)
				(type solid)
			)
			(layer "B.Fab")
		)
		(fp_line
			(start 0.599 0)
			(end 0.201 0)
			(stroke
				(width 0.15)
				(type solid)
			)
			(layer "B.Fab")
		)
		(fp_rect
			(start 0.848 -0.4)
			(end -0.85 0.402)
			(stroke
				(width 0.15)
				(type solid)
			)
			(fill no)
			(layer "B.Fab")
		)
		(fp_text user "${REFERENCE}"
			(at -1.4224 -5.999 0)
			(layer "B.Fab")
			(effects
				(font
					(size 0.7 0.7)
					(thickness 0.15)
				)
				(justify right top mirror)
			)
		)
		(fp_text user "License: Apache-2.0"
			(at -1.4224 -3.599 0)
			(layer "B.Fab")
			(effects
				(font
					(size 0.7 0.7)
					(thickness 0.15)
				)
				(justify right top mirror)
			)
		)
		(fp_text user "Author: Antmicro"
			(at -1.4224 -4.799 0)
			(layer "B.Fab")
			(effects
				(font
					(size 0.7 0.7)
					(thickness 0.15)
				)
				(justify right top mirror)
			)
		)
		(pad "1" smd roundrect
			(at -0.7 0 180)
			(size 0.8 1)
			(layers "B.Cu" "B.Mask" "B.Paste")
			(roundrect_rratio 0.2)
			(net 1 "GND")
			(pinfunction "C")
			(pintype "passive")
		)
		(pad "2" smd roundrect
			(at 0.7 0 180)
			(size 0.8 1)
			(layers "B.Cu" "B.Mask" "B.Paste")
			(roundrect_rratio 0.2)
			(net 542 "Net-(D29-A)")
			(pinfunction "A")
			(pintype "passive")
		)
	)
)
